(kicad_pcb
	(version 20260206)
	(generator "pcbnew")
	(generator_version "10.0")
	(general
		(thickness 1.6)
		(legacy_teardrops no)
	)
	(paper "A4")
	(title_block
		(title "Wiwynn_Tioga_Pass_MB.brd")
		(comment 1 "Tioga Pass / footprints 1635-1641 of 4770")
	)
	(layers
		(0 "F.Cu" signal "TOP")
		(4 "In1.Cu" signal "L2GND")
		(6 "In2.Cu" signal "L3")
		(8 "In3.Cu" signal "L4GND")
		(10 "In4.Cu" signal "L5")
		(12 "In5.Cu" signal "L6GND")
		(14 "In6.Cu" signal "L7VCC")
		(16 "In7.Cu" signal "L8VCC")
		(18 "In8.Cu" signal "L9GND")
		(20 "In9.Cu" signal "L10")
		(22 "In10.Cu" signal "L11GND")
		(24 "In11.Cu" signal "L12")
		(26 "In12.Cu" signal "L13GND")
		(2 "B.Cu" signal "BOTTOM")
		(9 "F.Adhes" user "F.Adhesive")
		(11 "B.Adhes" user "B.Adhesive")
		(13 "F.Paste" user "Package Geometry/Pastemask Top")
		(15 "B.Paste" user "Package Geometry/Pastemask Bottom")
		(5 "F.SilkS" user "Ref Des/Silkscreen Top")
		(7 "B.SilkS" user "Ref Des/Silkscreen Bottom")
		(1 "F.Mask" user "Board Geometry/Soldermask Top")
		(3 "B.Mask" user "Board Geometry/Soldermask Bottom")
		(17 "Dwgs.User" user "User.Drawings")
		(19 "Cmts.User" user "User.Comments")
		(21 "Eco1.User" user "User.Eco1")
		(23 "Eco2.User" user "User.Eco2")
		(25 "Edge.Cuts" user "Board Geometry/Outline")
		(27 "Margin" user)
		(31 "F.CrtYd" user "Package Geometry/Place Bound Top")
		(29 "B.CrtYd" user "Package Geometry/Place Bound Bottom")
		(35 "F.Fab" user "Ref Des/Assembly Top")
		(33 "B.Fab" user "Ref Des/Assembly Bottom")
	)
	(footprint ""
		(layer "F.Cu")
		(at 312.142124 -35.623754)
		(property "Reference" "R1W31"
			(at -0.8382 -0.67818 0)
			(unlocked yes)
			(layer "F.SilkS")
			(effects
				(font
					(size 0.4064 0.254)
					(thickness 0.1524)
				)
				(justify left)
			)
		)
		(property "Value" ""
			(at 0 0 0)
			(layer "F.Fab")
			(effects
				(font
					(size 1.27 1.27)
				)
			)
		)
		(duplicate_pad_numbers_are_jumpers no)
		(fp_poly
			(pts
				(xy -0.2794 -0.1016) (xy 0.2794 -0.1016) (xy 0.2794 0.9906) (xy -0.2794 0.9906)
			)
			(stroke
				(width 0)
				(type default)
			)
			(fill no)
			(layer "F.CrtYd")
		)
		(fp_line
			(start -0.2794 -0.1016)
			(end -0.2794 0.9906)
			(stroke
				(width 0.1)
				(type default)
			)
			(layer "F.Fab")
		)
		(fp_line
			(start -0.2794 0.9906)
			(end 0.2794 0.9906)
			(stroke
				(width 0.1)
				(type default)
			)
			(layer "F.Fab")
		)
		(fp_line
			(start 0.2794 -0.1016)
			(end -0.2794 -0.1016)
			(stroke
				(width 0.1)
				(type default)
			)
			(layer "F.Fab")
		)
		(fp_line
			(start 0.2794 0.9906)
			(end 0.2794 -0.1016)
			(stroke
				(width 0.1)
				(type default)
			)
			(layer "F.Fab")
		)
		(pad "1" smd rect
			(at 0 0)
			(size 0.508 0.508)
			(layers "F.Cu" "F.Mask" "F.Paste")
			(net "FM_ADR_COMPLETE_R")
		)
		(pad "2" smd rect
			(at 0 0.889)
			(size 0.508 0.508)
			(layers "F.Cu" "F.Mask" "F.Paste")
			(net "FM_ADR_COMPLETE_CPU1_R")
		)
		(zone
			(layer "F.Cu")
			(hatch none 0.5)
			(connect_pads
				(clearance 0)
			)
			(min_thickness 0.25)
			(keepout
				(tracks allowed)
				(vias not_allowed)
				(pads allowed)
				(copperpour not_allowed)
				(footprints allowed)
			)
			(placement
				(enabled no)
				(sheetname "")
			)
			(fill
				(thermal_gap 0.5)
				(thermal_bridge_width 0.5)
				(island_removal_mode 0)
			)
			(polygon
				(pts
					(xy 311.888124 -35.369754) (xy 312.396124 -35.369754) (xy 312.396124 -34.988754) (xy 311.888124 -34.988754)
				)
			)
		)
		(zone
			(layer "F.Cu")
			(hatch none 0.5)
			(connect_pads
				(clearance 0)
			)
			(min_thickness 0.25)
			(keepout
				(tracks not_allowed)
				(vias allowed)
				(pads allowed)
				(copperpour not_allowed)
				(footprints allowed)
			)
			(placement
				(enabled no)
				(sheetname "")
			)
			(fill
				(thermal_gap 0.5)
				(thermal_bridge_width 0.5)
				(island_removal_mode 0)
			)
			(polygon
				(pts
					(xy 311.888124 -34.988754) (xy 312.396124 -34.988754) (xy 312.396124 -35.369754) (xy 311.888124 -35.369754)
				)
			)
		)
	)
	(footprint ""
		(layer "F.Cu")
		(at 108.368592 -77.429614)
		(property "Reference" "C3D11"
			(at 0 0 0)
			(layer "F.SilkS")
			(hide yes)
			(effects
				(font
					(size 1.27 1.27)
				)
			)
		)
		(property "Value" ""
			(at 0 0 0)
			(layer "F.Fab")
			(effects
				(font
					(size 1.27 1.27)
				)
			)
		)
		(duplicate_pad_numbers_are_jumpers no)
		(fp_poly
			(pts
				(xy -0.4953 -0.2032) (xy 0.4953 -0.2032) (xy 0.4953 1.6002) (xy -0.4953 1.6002)
			)
			(stroke
				(width 0)
				(type default)
			)
			(fill no)
			(layer "F.CrtYd")
		)
		(fp_line
			(start -0.4953 -0.2032)
			(end 0.4953 -0.2032)
			(stroke
				(width 0.1)
				(type default)
			)
			(layer "F.Fab")
		)
		(fp_line
			(start -0.4953 1.6002)
			(end -0.4953 -0.2032)
			(stroke
				(width 0.1)
				(type default)
			)
			(layer "F.Fab")
		)
		(fp_line
			(start 0.4953 -0.2032)
			(end 0.4953 1.6002)
			(stroke
				(width 0.1)
				(type default)
			)
			(layer "F.Fab")
		)
		(fp_line
			(start 0.4953 1.6002)
			(end -0.4953 1.6002)
			(stroke
				(width 0.1)
				(type default)
			)
			(layer "F.Fab")
		)
		(pad "1" smd rect
			(at 0 0)
			(size 0.762 0.889)
			(layers "F.Cu" "F.Mask" "F.Paste")
			(net "PVCCMCP_CPU1")
		)
		(pad "2" smd rect
			(at 0 1.397)
			(size 0.762 0.889)
			(layers "F.Cu" "F.Mask" "F.Paste")
			(net "GND")
		)
		(zone
			(layer "F.Cu")
			(hatch none 0.5)
			(connect_pads
				(clearance 0)
			)
			(min_thickness 0.25)
			(keepout
				(tracks not_allowed)
				(vias allowed)
				(pads allowed)
				(copperpour not_allowed)
				(footprints allowed)
			)
			(placement
				(enabled no)
				(sheetname "")
			)
			(fill
				(thermal_gap 0.5)
				(thermal_bridge_width 0.5)
				(island_removal_mode 0)
			)
			(polygon
				(pts
					(xy 107.987592 -76.985114) (xy 108.749592 -76.985114) (xy 108.749592 -76.477114) (xy 107.987592 -76.477114)
				)
			)
		)
	)
	(footprint ""
		(layer "F.Cu")
		(at 491.0455 -44.0944 90)
		(property "Reference" "R9E13"
			(at 0 0 90)
			(layer "F.SilkS")
			(hide yes)
			(effects
				(font
					(size 1.27 1.27)
				)
			)
		)
		(property "Value" ""
			(at 0 0 90)
			(layer "F.Fab")
			(effects
				(font
					(size 1.27 1.27)
				)
			)
		)
		(duplicate_pad_numbers_are_jumpers no)
		(fp_poly
			(pts
				(xy -0.2794 -0.1016) (xy 0.2794 -0.1016) (xy 0.2794 0.9906) (xy -0.2794 0.9906)
			)
			(stroke
				(width 0)
				(type default)
			)
			(fill no)
			(layer "F.CrtYd")
		)
		(fp_line
			(start 0.2794 -0.1016)
			(end -0.2794 -0.1016)
			(stroke
				(width 0.1)
				(type default)
			)
			(layer "F.Fab")
		)
		(fp_line
			(start -0.2794 -0.1016)
			(end -0.2794 0.9906)
			(stroke
				(width 0.1)
				(type default)
			)
			(layer "F.Fab")
		)
		(fp_line
			(start 0.2794 0.9906)
			(end 0.2794 -0.1016)
			(stroke
				(width 0.1)
				(type default)
			)
			(layer "F.Fab")
		)
		(fp_line
			(start -0.2794 0.9906)
			(end 0.2794 0.9906)
			(stroke
				(width 0.1)
				(type default)
			)
			(layer "F.Fab")
		)
		(pad "1" smd rect
			(at 0 0 90)
			(size 0.508 0.508)
			(layers "F.Cu" "F.Mask" "F.Paste")
			(net "RMII_BMC_PCH_SPRNGVLLE_TXEN")
		)
		(pad "2" smd rect
			(at 0 0.889 90)
			(size 0.508 0.508)
			(layers "F.Cu" "F.Mask" "F.Paste")
			(net "GND")
		)
		(zone
			(layer "F.Cu")
			(hatch none 0.5)
			(connect_pads
				(clearance 0)
			)
			(min_thickness 0.25)
			(keepout
				(tracks allowed)
				(vias not_allowed)
				(pads allowed)
				(copperpour not_allowed)
				(footprints allowed)
			)
			(placement
				(enabled no)
				(sheetname "")
			)
			(fill
				(thermal_gap 0.5)
				(thermal_bridge_width 0.5)
				(island_removal_mode 0)
			)
			(polygon
				(pts
					(xy 491.2995 -43.8404) (xy 491.2995 -44.3484) (xy 491.6805 -44.3484) (xy 491.6805 -43.8404)
				)
			)
		)
		(zone
			(layer "F.Cu")
			(hatch none 0.5)
			(connect_pads
				(clearance 0)
			)
			(min_thickness 0.25)
			(keepout
				(tracks not_allowed)
				(vias allowed)
				(pads allowed)
				(copperpour not_allowed)
				(footprints allowed)
			)
			(placement
				(enabled no)
				(sheetname "")
			)
			(fill
				(thermal_gap 0.5)
				(thermal_bridge_width 0.5)
				(island_removal_mode 0)
			)
			(polygon
				(pts
					(xy 491.6805 -43.8404) (xy 491.6805 -44.3484) (xy 491.2995 -44.3484) (xy 491.2995 -43.8404)
				)
			)
		)
	)
	(footprint ""
		(layer "F.Cu")
		(at 406.7302 -103.7336 -90)
		(property "Reference" "R8C23"
			(at 0 0 270)
			(layer "F.SilkS")
			(hide yes)
			(effects
				(font
					(size 1.27 1.27)
				)
			)
		)
		(property "Value" ""
			(at 0 0 270)
			(layer "F.Fab")
			(effects
				(font
					(size 1.27 1.27)
				)
			)
		)
		(duplicate_pad_numbers_are_jumpers no)
		(fp_poly
			(pts
				(xy -0.2794 -0.1016) (xy 0.2794 -0.1016) (xy 0.2794 0.9906) (xy -0.2794 0.9906)
			)
			(stroke
				(width 0)
				(type default)
			)
			(fill no)
			(layer "F.CrtYd")
		)
		(fp_line
			(start -0.2794 0.9906)
			(end 0.2794 0.9906)
			(stroke
				(width 0.1)
				(type default)
			)
			(layer "F.Fab")
		)
		(fp_line
			(start 0.2794 0.9906)
			(end 0.2794 -0.1016)
			(stroke
				(width 0.1)
				(type default)
			)
			(layer "F.Fab")
		)
		(fp_line
			(start -0.2794 -0.1016)
			(end -0.2794 0.9906)
			(stroke
				(width 0.1)
				(type default)
			)
			(layer "F.Fab")
		)
		(fp_line
			(start 0.2794 -0.1016)
			(end -0.2794 -0.1016)
			(stroke
				(width 0.1)
				(type default)
			)
			(layer "F.Fab")
		)
		(pad "1" smd rect
			(at 0 0 270)
			(size 0.508 0.508)
			(layers "F.Cu" "F.Mask" "F.Paste")
			(net "FM_GBE_LOM_DISABLE_N")
		)
		(pad "2" smd rect
			(at 0 0.889 270)
			(size 0.508 0.508)
			(layers "F.Cu" "F.Mask" "F.Paste")
			(net "FM_10GBE_LOM_DISABLE_N")
		)
		(zone
			(layer "F.Cu")
			(hatch none 0.5)
			(connect_pads
				(clearance 0)
			)
			(min_thickness 0.25)
			(keepout
				(tracks not_allowed)
				(vias allowed)
				(pads allowed)
				(copperpour not_allowed)
				(footprints allowed)
			)
			(placement
				(enabled no)
				(sheetname "")
			)
			(fill
				(thermal_gap 0.5)
				(thermal_bridge_width 0.5)
				(island_removal_mode 0)
			)
			(polygon
				(pts
					(xy 406.0952 -103.9876) (xy 406.0952 -103.4796) (xy 406.4762 -103.4796) (xy 406.4762 -103.9876)
				)
			)
		)
		(zone
			(layer "F.Cu")
			(hatch none 0.5)
			(connect_pads
				(clearance 0)
			)
			(min_thickness 0.25)
			(keepout
				(tracks allowed)
				(vias not_allowed)
				(pads allowed)
				(copperpour not_allowed)
				(footprints allowed)
			)
			(placement
				(enabled no)
				(sheetname "")
			)
			(fill
				(thermal_gap 0.5)
				(thermal_bridge_width 0.5)
				(island_removal_mode 0)
			)
			(polygon
				(pts
					(xy 406.4762 -103.9876) (xy 406.4762 -103.4796) (xy 406.0952 -103.4796) (xy 406.0952 -103.9876)
				)
			)
		)
	)
	(footprint ""
		(layer "F.Cu")
		(at 426.5295 -127.3175 -90)
		(property "Reference" "R8B10"
			(at 0 0 270)
			(layer "F.SilkS")
			(hide yes)
			(effects
				(font
					(size 1.27 1.27)
				)
			)
		)
		(property "Value" ""
			(at 0 0 270)
			(layer "F.Fab")
			(effects
				(font
					(size 1.27 1.27)
				)
			)
		)
		(duplicate_pad_numbers_are_jumpers no)
		(fp_poly
			(pts
				(xy -0.2794 -0.1016) (xy 0.2794 -0.1016) (xy 0.2794 0.9906) (xy -0.2794 0.9906)
			)
			(stroke
				(width 0)
				(type default)
			)
			(fill no)
			(layer "F.CrtYd")
		)
		(fp_line
			(start -0.2794 0.9906)
			(end 0.2794 0.9906)
			(stroke
				(width 0.1)
				(type default)
			)
			(layer "F.Fab")
		)
		(fp_line
			(start 0.2794 0.9906)
			(end 0.2794 -0.1016)
			(stroke
				(width 0.1)
				(type default)
			)
			(layer "F.Fab")
		)
		(fp_line
			(start -0.2794 -0.1016)
			(end -0.2794 0.9906)
			(stroke
				(width 0.1)
				(type default)
			)
			(layer "F.Fab")
		)
		(fp_line
			(start 0.2794 -0.1016)
			(end -0.2794 -0.1016)
			(stroke
				(width 0.1)
				(type default)
			)
			(layer "F.Fab")
		)
		(pad "1" smd rect
			(at 0 0 270)
			(size 0.508 0.508)
			(layers "F.Cu" "F.Mask" "F.Paste")
			(net "PVPP_ABC")
		)
		(pad "2" smd rect
			(at 0 0.889 270)
			(size 0.508 0.508)
			(layers "F.Cu" "F.Mask" "F.Paste")
			(net "IRQ_HFI0_CPU0_LVT2_N")
		)
		(zone
			(layer "F.Cu")
			(hatch none 0.5)
			(connect_pads
				(clearance 0)
			)
			(min_thickness 0.25)
			(keepout
				(tracks not_allowed)
				(vias allowed)
				(pads allowed)
				(copperpour not_allowed)
				(footprints allowed)
			)
			(placement
				(enabled no)
				(sheetname "")
			)
			(fill
				(thermal_gap 0.5)
				(thermal_bridge_width 0.5)
				(island_removal_mode 0)
			)
			(polygon
				(pts
					(xy 425.8945 -127.5715) (xy 425.8945 -127.0635) (xy 426.2755 -127.0635) (xy 426.2755 -127.5715)
				)
			)
		)
		(zone
			(layer "F.Cu")
			(hatch none 0.5)
			(connect_pads
				(clearance 0)
			)
			(min_thickness 0.25)
			(keepout
				(tracks allowed)
				(vias not_allowed)
				(pads allowed)
				(copperpour not_allowed)
				(footprints allowed)
			)
			(placement
				(enabled no)
				(sheetname "")
			)
			(fill
				(thermal_gap 0.5)
				(thermal_bridge_width 0.5)
				(island_removal_mode 0)
			)
			(polygon
				(pts
					(xy 426.2755 -127.5715) (xy 426.2755 -127.0635) (xy 425.8945 -127.0635) (xy 425.8945 -127.5715)
				)
			)
		)
	)
	(footprint ""
		(layer "F.Cu")
		(at 449.69938 -37.1475 90)
		(property "Reference" "R25W20"
			(at 0 0 90)
			(layer "F.SilkS")
			(hide yes)
			(effects
				(font
					(size 1.27 1.27)
				)
			)
		)
		(property "Value" "*"
			(at 0.064008 -4.108196 90)
			(unlocked yes)
			(layer "F.Fab")
			(hide yes)
			(effects
				(font
					(size 1.27 1.016)
					(thickness 0.1524)
				)
			)
		)
		(property "Device Type" "120R2F-GP_RCL_GP-120R2F-GP,64.A"
			(at 0.064008 -5.632196 90)
			(unlocked yes)
			(layer "F.Fab")
			(hide yes)
			(effects
				(font
					(size 1.27 1.016)
					(thickness 0.1524)
				)
			)
		)
		(duplicate_pad_numbers_are_jumpers no)
		(fp_line
			(start 0.508 -0.9398)
			(end -0.508 -0.9398)
			(stroke
				(width 0.1524)
				(type default)
			)
			(layer "F.SilkS")
		)
		(fp_line
			(start -0.508 -0.9398)
			(end -0.508 0.9398)
			(stroke
				(width 0.1524)
				(type default)
			)
			(layer "F.SilkS")
		)
		(fp_rect
			(start -0.508 0.9398)
			(end 0.508 -0.9398)
			(stroke
				(width 0)
				(type default)
			)
			(fill no)
			(layer "F.CrtYd")
		)
		(fp_rect
			(start -0.508 0.9398)
			(end 0.508 -0.9398)
			(stroke
				(width 0)
				(type default)
			)
			(fill no)
			(layer "F.Fab")
		)
		(pad "1" smd custom
			(at 0 -0.4445 90)
			(size 0.1397 0.1397)
			(layers "F.Cu" "F.Mask" "F.Paste")
			(net "GND")
			(options
				(clearance outline)
				(anchor circle)
			)
			(primitives
				(gr_poly
					(pts
						(arc
							(start -0.1778 -0.2794)
							(mid -0.249642 -0.249642)
							(end -0.2794 -0.1778)
						)
						(arc
							(start -0.2794 0.1778)
							(mid -0.249642 0.249642)
							(end -0.1778 0.2794)
						)
						(arc
							(start 0.1778 0.2794)
							(mid 0.249642 0.249642)
							(end 0.2794 0.1778)
						)
						(arc
							(start 0.2794 -0.1778)
							(mid 0.249642 -0.249642)
							(end 0.1778 -0.2794)
						)
					)
					(width 0)
					(fill yes)
				)
			)
		)
		(pad "2" smd custom
			(at 0 0.4445 90)
			(size 0.1397 0.1397)
			(layers "F.Cu" "F.Mask" "F.Paste")
			(net "BMC_M_A8")
			(options
				(clearance outline)
				(anchor circle)
			)
			(primitives
				(gr_poly
					(pts
						(arc
							(start -0.1778 -0.2794)
							(mid -0.249642 -0.249642)
							(end -0.2794 -0.1778)
						)
						(arc
							(start -0.2794 0.1778)
							(mid -0.249642 0.249642)
							(end -0.1778 0.2794)
						)
						(arc
							(start 0.1778 0.2794)
							(mid 0.249642 0.249642)
							(end 0.2794 0.1778)
						)
						(arc
							(start 0.2794 -0.1778)
							(mid 0.249642 -0.249642)
							(end 0.1778 -0.2794)
						)
					)
					(width 0)
					(fill yes)
				)
			)
		)
	)
	(footprint ""
		(layer "F.Cu")
		(at 155.2956 -12.954 90)
		(property "Reference" "C3G4"
			(at 0 0 90)
			(layer "F.SilkS")
			(hide yes)
			(effects
				(font
					(size 1.27 1.27)
				)
			)
		)
		(property "Value" ""
			(at 0 0 90)
			(layer "F.Fab")
			(effects
				(font
					(size 1.27 1.27)
				)
			)
		)
		(duplicate_pad_numbers_are_jumpers no)
		(fp_poly
			(pts
				(xy -0.4953 -0.2032) (xy 0.4953 -0.2032) (xy 0.4953 1.6002) (xy -0.4953 1.6002)
			)
			(stroke
				(width 0)
				(type default)
			)
			(fill no)
			(layer "F.CrtYd")
		)
		(fp_line
			(start 0.4953 -0.2032)
			(end 0.4953 1.6002)
			(stroke
				(width 0.1)
				(type default)
			)
			(layer "F.Fab")
		)
		(fp_line
			(start -0.4953 -0.2032)
			(end 0.4953 -0.2032)
			(stroke
				(width 0.1)
				(type default)
			)
			(layer "F.Fab")
		)
		(fp_line
			(start 0.4953 1.6002)
			(end -0.4953 1.6002)
			(stroke
				(width 0.1)
				(type default)
			)
			(layer "F.Fab")
		)
		(fp_line
			(start -0.4953 1.6002)
			(end -0.4953 -0.2032)
			(stroke
				(width 0.1)
				(type default)
			)
			(layer "F.Fab")
		)
		(pad "1" smd rect
			(at 0 0 90)
			(size 0.762 0.889)
			(layers "F.Cu" "F.Mask" "F.Paste")
			(net "PVPP_GHJ")
		)
		(pad "2" smd rect
			(at 0 1.397 90)
			(size 0.762 0.889)
			(layers "F.Cu" "F.Mask" "F.Paste")
			(net "GND")
		)
		(zone
			(layer "F.Cu")
			(hatch none 0.5)
			(connect_pads
				(clearance 0)
			)
			(min_thickness 0.25)
			(keepout
				(tracks not_allowed)
				(vias allowed)
				(pads allowed)
				(copperpour not_allowed)
				(footprints allowed)
			)
			(placement
				(enabled no)
				(sheetname "")
			)
			(fill
				(thermal_gap 0.5)
				(thermal_bridge_width 0.5)
				(island_removal_mode 0)
			)
			(polygon
				(pts
					(xy 155.7401 -12.573) (xy 155.7401 -13.335) (xy 156.2481 -13.335) (xy 156.2481 -12.573)
				)
			)
		)
	)
)
